# S9S_MB_2U (Grand Teton) — schematic netlist excerpt (pin names and nets, part order shuffled) for the footprints in the layout excerpt that follows; sources: Cadence DE-HDL packaged netlist, KiCad conversion of 03242023_DA0F0TMBIJ0_F0T_Motherboard_J_brd_V01_OCP.brd

PR1794  Q_RES  3.3 1% CHIP  pkg 0402LF  page 293 : A = SW_PVCCINFAON_CPU1_BOOT1 ; B = SW_PVCCINFAON_CPU1_BOOT1_R

DB3  TDR_3P  EMPTY  pkg TH2  page 309
  GND  = T1_GND
  IO1  = TDR_SE_40_OHM_IN2
  IO2  = TDR_SE_40_OHM_IN2

R4704  Q_RES  560 1% CHIP  pkg 0402LF  page 255 : A = LED_P12V_AUX_R2 ; B = LED_P12V_AUX_R3

(kicad_pcb
	(version 20260206)
	(generator "pcbnew")
	(generator_version "10.0")
	(general
		(thickness 1.6)
		(legacy_teardrops no)
	)
	(paper "A4")
	(title_block
		(title "03242023_DA0F0TMBIJ0_F0T_Motherboard_J_brd_V01_OCP.brd")
		(comment 1 "Grand Teton / footprints 3030-3032 of 6105")
	)
	(layers
		(0 "F.Cu" signal "TOP")
		(4 "In1.Cu" signal "GND")
		(6 "In2.Cu" signal "IN1")
		(8 "In3.Cu" signal "GND1")
		(10 "In4.Cu" signal "IN2")
		(12 "In5.Cu" signal "GND2")
		(14 "In6.Cu" signal "IN3")
		(16 "In7.Cu" signal "GND3")
		(18 "In8.Cu" signal "VCC")
		(20 "In9.Cu" signal "VCC1")
		(22 "In10.Cu" signal "GND4")
		(24 "In11.Cu" signal "IN4")
		(26 "In12.Cu" signal "GND5")
		(28 "In13.Cu" signal "IN5")
		(30 "In14.Cu" signal "GND6")
		(32 "In15.Cu" signal "IN6")
		(34 "In16.Cu" signal "GND7")
		(2 "B.Cu" signal "BOTTOM")
		(9 "F.Adhes" user "F.Adhesive")
		(11 "B.Adhes" user "B.Adhesive")
		(13 "F.Paste" user "Package Geometry/Pastemask Top")
		(15 "B.Paste" user "Package Geometry/Pastemask Bottom")
		(5 "F.SilkS" user "Ref Des/Silkscreen Top")
		(7 "B.SilkS" user "Ref Des/Silkscreen Bottom")
		(1 "F.Mask" user "Board Geometry/Soldermask Top")
		(3 "B.Mask" user "Board Geometry/Soldermask Bottom")
		(17 "Dwgs.User" user "User.Drawings")
		(19 "Cmts.User" user "User.Comments")
		(21 "Eco1.User" user "User.Eco1")
		(23 "Eco2.User" user "User.Eco2")
		(25 "Edge.Cuts" user "Board Geometry/Outline")
		(27 "Margin" user)
		(31 "F.CrtYd" user "Package Geometry/Place Bound Top")
		(29 "B.CrtYd" user "Package Geometry/Place Bound Bottom")
		(35 "F.Fab" user "Ref Des/Assembly Top")
		(33 "B.Fab" user "Ref Des/Assembly Bottom")
	)
	(footprint ""
		(layer "F.Cu")
		(at 506.259338 -427.45025 180)
		(property "Reference" "DB3"
			(at -2.693924 -0.263398 90)
			(unlocked yes)
			(layer "F.SilkS")
			(effects
				(font
					(size 0.7874 0.5842)
					(thickness 0.1524)
				)
				(justify left)
			)
		)
		(property "Value" ""
			(at 0 0 180)
			(layer "F.Fab")
			(effects
				(font
					(size 1.27 1.27)
				)
			)
		)
		(duplicate_pad_numbers_are_jumpers no)
		(fp_line
			(start 3.330702 -4.771136)
			(end 0 4.011168)
			(stroke
				(width 0.1524)
				(type default)
			)
			(layer "F.SilkS")
		)
		(fp_line
			(start 0 4.011168)
			(end -3.330702 -4.771136)
			(stroke
				(width 0.1524)
				(type default)
			)
			(layer "F.SilkS")
		)
		(fp_line
			(start -3.330702 -4.771136)
			(end 3.330702 -4.771136)
			(stroke
				(width 0.1524)
				(type default)
			)
			(layer "F.SilkS")
		)
		(fp_line
			(start 3.330702 -4.771136)
			(end 0 4.011168)
			(stroke
				(width 0.1)
				(type default)
			)
			(layer "F.Fab")
		)
		(fp_line
			(start 0 4.011168)
			(end -3.330702 -4.771136)
			(stroke
				(width 0.1)
				(type default)
			)
			(layer "F.Fab")
		)
		(fp_line
			(start -3.330702 -4.771136)
			(end 3.330702 -4.771136)
			(stroke
				(width 0.1)
				(type default)
			)
			(layer "F.Fab")
		)
		(pad "1" thru_hole circle
			(at 0 0 180)
			(size 2.159 2.159)
			(drill 1.7018)
			(layers "*.Cu" "*.Mask")
			(remove_unused_layers no)
			(net "T1_GND")
			(clearance 0.0254)
			(thermal_gap 0.0254)
		)
		(pad "2" thru_hole circle
			(at -1.27 -3.348736 180)
			(size 2.159 2.159)
			(drill 1.7018)
			(layers "*.Cu" "*.Mask")
			(remove_unused_layers no)
			(net "TDR_SE_40_OHM_IN2")
			(clearance 0.0254)
			(thermal_gap 0.0254)
		)
		(pad "3" thru_hole circle
			(at 1.27 -3.348736 180)
			(size 2.159 2.159)
			(drill 1.7018)
			(layers "*.Cu" "*.Mask")
			(remove_unused_layers no)
			(net "TDR_SE_40_OHM_IN2")
			(clearance 0.0254)
			(thermal_gap 0.0254)
		)
	)
	(footprint ""
		(layer "F.Cu")
		(at 50.43551 -157.172914 180)
		(property "Reference" "PR1794"
			(at 0 0 180)
			(layer "F.SilkS")
			(hide yes)
			(effects
				(font
					(size 1.27 1.27)
				)
			)
		)
		(property "Value" ""
			(at 0 0 180)
			(layer "F.Fab")
			(effects
				(font
					(size 1.27 1.27)
				)
			)
		)
		(duplicate_pad_numbers_are_jumpers no)
		(fp_line
			(start 0.7874 0.4064)
			(end -0.7874 0.4064)
			(stroke
				(width 0.1524)
				(type default)
			)
			(layer "F.SilkS")
		)
		(fp_line
			(start 0.7874 -0.4064)
			(end 0.7874 0.4064)
			(stroke
				(width 0.1524)
				(type default)
			)
			(layer "F.SilkS")
		)
		(fp_line
			(start -0.7874 0.4064)
			(end -0.7874 -0.4064)
			(stroke
				(width 0.1524)
				(type default)
			)
			(layer "F.SilkS")
		)
		(fp_line
			(start -0.7874 -0.4064)
			(end 0.7874 -0.4064)
			(stroke
				(width 0.1524)
				(type default)
			)
			(layer "F.SilkS")
		)
		(fp_line
			(start 0.67945 0.3048)
			(end 0.120396 0.3048)
			(stroke
				(width 0.1)
				(type default)
			)
			(layer "F.Fab")
		)
		(fp_line
			(start 0.67945 -0.3048)
			(end 0.67945 0.3048)
			(stroke
				(width 0.1)
				(type default)
			)
			(layer "F.Fab")
		)
		(fp_line
			(start 0.12065 -0.2794)
			(end 0.12065 -0.3048)
			(stroke
				(width 0.1)
				(type default)
			)
			(layer "F.Fab")
		)
		(fp_line
			(start 0.12065 -0.3048)
			(end 0.67945 -0.3048)
			(stroke
				(width 0.1)
				(type default)
			)
			(layer "F.Fab")
		)
		(fp_line
			(start 0.120396 0.3048)
			(end 0.120396 0.2794)
			(stroke
				(width 0.1)
				(type default)
			)
			(layer "F.Fab")
		)
		(fp_line
			(start 0.120396 0.2794)
			(end -0.12065 0.2794)
			(stroke
				(width 0.1)
				(type default)
			)
			(layer "F.Fab")
		)
		(fp_line
			(start -0.12065 0.3048)
			(end -0.67945 0.3048)
			(stroke
				(width 0.1)
				(type default)
			)
			(layer "F.Fab")
		)
		(fp_line
			(start -0.12065 0.2794)
			(end -0.12065 0.3048)
			(stroke
				(width 0.1)
				(type default)
			)
			(layer "F.Fab")
		)
		(fp_line
			(start -0.12065 -0.2794)
			(end 0.12065 -0.2794)
			(stroke
				(width 0.1)
				(type default)
			)
			(layer "F.Fab")
		)
		(fp_line
			(start -0.12065 -0.305054)
			(end -0.12065 -0.2794)
			(stroke
				(width 0.1)
				(type default)
			)
			(layer "F.Fab")
		)
		(fp_line
			(start -0.67945 0.3048)
			(end -0.67945 -0.305054)
			(stroke
				(width 0.1)
				(type default)
			)
			(layer "F.Fab")
		)
		(fp_line
			(start -0.67945 -0.305054)
			(end -0.12065 -0.305054)
			(stroke
				(width 0.1)
				(type default)
			)
			(layer "F.Fab")
		)
		(pad "1" smd circle
			(at -0.40005 0 180)
			(size 0 0)
			(layers "F.Cu" "F.Mask" "F.Paste")
			(net "SW_PVCCINFAON_CPU1_BOOT1")
		)
		(pad "2" smd circle
			(at 0.40005 0 180)
			(size 0 0)
			(layers "F.Cu" "F.Mask" "F.Paste")
			(net "SW_PVCCINFAON_CPU1_BOOT1_R")
		)
	)
	(footprint ""
		(layer "F.Cu")
		(at 368.7318 -74.3458 -90)
		(property "Reference" "R4704"
			(at 0 0 270)
			(layer "F.SilkS")
			(hide yes)
			(effects
				(font
					(size 1.27 1.27)
				)
			)
		)
		(property "Value" ""
			(at 0 0 270)
			(layer "F.Fab")
			(effects
				(font
					(size 1.27 1.27)
				)
			)
		)
		(duplicate_pad_numbers_are_jumpers no)
		(fp_line
			(start -0.7874 0.4064)
			(end -0.7874 -0.4064)
			(stroke
				(width 0.1524)
				(type default)
			)
			(layer "F.SilkS")
		)
		(fp_line
			(start 0.7874 0.4064)
			(end -0.7874 0.4064)
			(stroke
				(width 0.1524)
				(type default)
			)
			(layer "F.SilkS")
		)
		(fp_line
			(start -0.7874 -0.4064)
			(end 0.7874 -0.4064)
			(stroke
				(width 0.1524)
				(type default)
			)
			(layer "F.SilkS")
		)
		(fp_line
			(start 0.7874 -0.4064)
			(end 0.7874 0.4064)
			(stroke
				(width 0.1524)
				(type default)
			)
			(layer "F.SilkS")
		)
		(fp_line
			(start -0.67945 0.3048)
			(end -0.67945 -0.305054)
			(stroke
				(width 0.1)
				(type default)
			)
			(layer "F.Fab")
		)
		(fp_line
			(start -0.12065 0.3048)
			(end -0.67945 0.3048)
			(stroke
				(width 0.1)
				(type default)
			)
			(layer "F.Fab")
		)
		(fp_line
			(start 0.120396 0.3048)
			(end 0.120396 0.2794)
			(stroke
				(width 0.1)
				(type default)
			)
			(layer "F.Fab")
		)
		(fp_line
			(start 0.67945 0.3048)
			(end 0.120396 0.3048)
			(stroke
				(width 0.1)
				(type default)
			)
			(layer "F.Fab")
		)
		(fp_line
			(start -0.12065 0.2794)
			(end -0.12065 0.3048)
			(stroke
				(width 0.1)
				(type default)
			)
			(layer "F.Fab")
		)
		(fp_line
			(start 0.120396 0.2794)
			(end -0.12065 0.2794)
			(stroke
				(width 0.1)
				(type default)
			)
			(layer "F.Fab")
		)
		(fp_line
			(start -0.12065 -0.2794)
			(end 0.12065 -0.2794)
			(stroke
				(width 0.1)
				(type default)
			)
			(layer "F.Fab")
		)
		(fp_line
			(start 0.12065 -0.2794)
			(end 0.12065 -0.3048)
			(stroke
				(width 0.1)
				(type default)
			)
			(layer "F.Fab")
		)
		(fp_line
			(start 0.12065 -0.3048)
			(end 0.67945 -0.3048)
			(stroke
				(width 0.1)
				(type default)
			)
			(layer "F.Fab")
		)
		(fp_line
			(start 0.67945 -0.3048)
			(end 0.67945 0.3048)
			(stroke
				(width 0.1)
				(type default)
			)
			(layer "F.Fab")
		)
		(fp_line
			(start -0.67945 -0.305054)
			(end -0.12065 -0.305054)
			(stroke
				(width 0.1)
				(type default)
			)
			(layer "F.Fab")
		)
		(fp_line
			(start -0.12065 -0.305054)
			(end -0.12065 -0.2794)
			(stroke
				(width 0.1)
				(type default)
			)
			(layer "F.Fab")
		)
		(pad "1" smd circle
			(at -0.40005 0 270)
			(size 0 0)
			(layers "F.Cu" "F.Mask" "F.Paste")
			(net "LED_P12V_AUX_R2")
		)
		(pad "2" smd circle
			(at 0.40005 0 270)
			(size 0 0)
			(layers "F.Cu" "F.Mask" "F.Paste")
			(net "LED_P12V_AUX_R3")
		)
	)
)
